# Stackup_F0T_Expander_BD_18L_3p09mm_EM-890K_VL411_Rev1_20221220.xls — Special processing (pcb-stackup)
| Special processing : |  |
| Golden Finger(金手指) | No |
| VIPPO(Via in Pad樹脂填孔) | Yes |
| Back Drill(背鑽) with epoxy plug/fill | Yes |
| Back Drill(背鑽) without epoxy plug/fill | No |
| Laser Drill(雷射鑽孔) | No |
| Low profile oxide(低棕化) | Yes |
| Multi-lamination(多次壓合) | No |
